(kicad_pcb
	(version 20221018)
	(generator pcbnew)
	(general
    (thickness 1.518)
  )
	(paper "A4")
	(title_block
    (title "Kria K26 Devboard")
    (date "2024-03-26")
    (rev "1.2.5")
    (comment 1 "www.antmicro.com")
    (comment 2 "Antmicro Ltd.")
		(comment 9 "footprints 572-580 of 660")
	)
	(layers
    (0 "F.Cu" mixed)
    (1 "In1.Cu" power)
    (2 "In2.Cu" mixed)
    (3 "In3.Cu" power)
    (4 "In4.Cu" mixed)
    (5 "In5.Cu" power)
    (6 "In6.Cu" mixed)
    (31 "B.Cu" power)
    (32 "B.Adhes" user "B.Adhesive")
    (33 "F.Adhes" user "F.Adhesive")
    (34 "B.Paste" user)
    (35 "F.Paste" user)
    (36 "B.SilkS" user "B.Silkscreen")
    (37 "F.SilkS" user "F.Silkscreen")
    (38 "B.Mask" user)
    (39 "F.Mask" user)
    (40 "Dwgs.User" user "User.Drawings")
    (41 "Cmts.User" user "User.Comments")
    (42 "Eco1.User" user "User.Eco1")
    (43 "Eco2.User" user "User.Eco2")
    (44 "Edge.Cuts" user)
    (45 "Margin" user)
    (46 "B.CrtYd" user "B.Courtyard")
    (47 "F.CrtYd" user "F.Courtyard")
    (48 "B.Fab" user)
    (49 "F.Fab" user)
  )
	(footprint "kria-k26-devboard-footprints:R_0402_1005Metric" (layer "B.Cu")
    (at 173.225 125.35 90)
    (descr "Resistor SMD 0402")
    (tags "resistor SMD 0402")
    (property "Author" "Antmicro")
    (property "License" "Apache-2.0")
    (property "MPN" "CR0402-FX-1003GLF")
    (property "Manufacturer" "Bourns")
    (property "Sheetfile" "dc-dc-conventers.kicad_sch")
    (property "Sheetname" "DC/DC conventers")
    (property "Tolerance" "1%")
    (property "Val" "100k")
    (property "ki_description" "100k resistor in 0402 package with 1% tolerance")
    (attr smd)
    (fp_text reference "R119" (at 1.4 1.325 270) (layer "B.SilkS")
        (effects (font (size 0.7 0.7) (thickness 0.15)) (justify left bottom mirror))
    )
    (fp_text value "R_100k_0402" (at 0 -1.4 270) (layer "B.Fab") hide
        (effects (font (size 0.7 0.7) (thickness 0.15)) (justify left bottom mirror))
    )
    (fp_text user "License: Apache-2.0" (at -0.95 -5.169 270) (layer "B.Fab") hide
        (effects (font (size 0.7 0.7) (thickness 0.15)) (justify left bottom mirror))
    )
    (fp_text user "Author: Antmicro" (at -0.95 -4.169 270) (layer "B.Fab") hide
        (effects (font (size 0.7 0.7) (thickness 0.15)) (justify left bottom mirror))
    )
    (fp_text user "${REFERENCE}" (at -0.95 -3.168 270) (layer "B.Fab") hide
        (effects (font (size 0.7 0.7) (thickness 0.15)) (justify left bottom mirror))
    )
    (fp_rect (start -0.93 0.47) (end 0.93 -0.47)
      (stroke (width 0.05) (type solid)) (fill none) (layer "B.CrtYd"))
    (fp_rect (start -0.5 0.25) (end 0.5 -0.25)
      (stroke (width 0.15) (type solid)) (fill none) (layer "B.Fab"))
    (pad "1" smd roundrect (at -0.485 0 90) (size 0.59 0.64) (layers "B.Cu" "B.Paste" "B.Mask") (roundrect_rratio 0.25)
      (net 686 "Net-(U48-EN)") (pintype "passive"))
    (pad "2" smd roundrect (at 0.485 0 90) (size 0.59 0.64) (layers "B.Cu" "B.Paste" "B.Mask") (roundrect_rratio 0.25)
      (net 14 "/Power Supply/DC/DC conventers/DC_MAIN_BUS") (pintype "passive"))
  )
	(footprint "kria-k26-devboard-footprints:R_0402_1005Metric" (layer "B.Cu")
    (at 176.29 126.95 180)
    (descr "Resistor SMD 0402")
    (tags "resistor SMD 0402")
    (property "Author" "Antmicro")
    (property "License" "Apache-2.0")
    (property "MPN" "CR0402-FX-2201GLF")
    (property "Manufacturer" "Bourns")
    (property "Sheetfile" "dc-dc-conventers.kicad_sch")
    (property "Sheetname" "DC/DC conventers")
    (property "Tolerance" "1%")
    (property "Val" "2k2")
    (property "ki_description" "2k2 resistor in 0402 package with 1% tolerance")
    (attr smd)
    (fp_text reference "R120" (at -1.33 0.55) (layer "B.SilkS")
        (effects (font (size 0.7 0.7) (thickness 0.15)) (justify left bottom mirror))
    )
    (fp_text value "R_2k2_0402" (at 0 -1.4) (layer "B.Fab") hide
        (effects (font (size 0.7 0.7) (thickness 0.15)) (justify left bottom mirror))
    )
    (fp_text user "License: Apache-2.0" (at -0.95 -5.169) (layer "B.Fab") hide
        (effects (font (size 0.7 0.7) (thickness 0.15)) (justify left bottom mirror))
    )
    (fp_text user "${REFERENCE}" (at -0.95 -3.168) (layer "B.Fab") hide
        (effects (font (size 0.7 0.7) (thickness 0.15)) (justify left bottom mirror))
    )
    (fp_text user "Author: Antmicro" (at -0.95 -4.169) (layer "B.Fab") hide
        (effects (font (size 0.7 0.7) (thickness 0.15)) (justify left bottom mirror))
    )
    (fp_rect (start -0.93 0.47) (end 0.93 -0.47)
      (stroke (width 0.05) (type solid)) (fill none) (layer "B.CrtYd"))
    (fp_rect (start -0.5 0.25) (end 0.5 -0.25)
      (stroke (width 0.15) (type solid)) (fill none) (layer "B.Fab"))
    (pad "1" smd roundrect (at -0.485 0 180) (size 0.59 0.64) (layers "B.Cu" "B.Paste" "B.Mask") (roundrect_rratio 0.25)
      (net 329 "Net-(D12-Pad1)") (pintype "passive"))
    (pad "2" smd roundrect (at 0.485 0 180) (size 0.59 0.64) (layers "B.Cu" "B.Paste" "B.Mask") (roundrect_rratio 0.25)
      (net 773 "/Power Supply/DC/DC conventers/SOM_5V_OUT") (pintype "passive"))
  )
	(footprint "kria-k26-devboard-footprints:C_0402_1005Metric" (layer "B.Cu")
    (at 144.57 74 180)
    (descr "Capacitor SMD 0402")
    (tags "capacitor SMD 0402")
    (property "Author" "Antmicro")
    (property "Dielectric" "")
    (property "License" "Apache-2.0")
    (property "MPN" "GRM155R71H392KA01D")
    (property "Manufacturer" "Murata")
    (property "Sheetfile" "dc-dc-conventers.kicad_sch")
    (property "Sheetname" "DC/DC conventers")
    (property "Val" "3n9")
    (property "Voltage" "")
    (property "ki_description" " ")
    (attr smd)
    (fp_text reference "C189" (at 0.825 -0.44) (layer "B.SilkS")
        (effects (font (size 0.7 0.7) (thickness 0.15)) (justify left bottom mirror))
    )
    (fp_text value "C_3n9_0402" (at 0 -1.4) (layer "B.Fab") hide
        (effects (font (size 0.7 0.7) (thickness 0.15)) (justify left bottom mirror))
    )
    (fp_text user "Author: Antmicro" (at -0.932 -4.17) (layer "B.Fab") hide
        (effects (font (size 0.7 0.7) (thickness 0.15)) (justify left bottom mirror))
    )
    (fp_text user "${REFERENCE}" (at -0.932 -3.168) (layer "B.Fab") hide
        (effects (font (size 0.7 0.7) (thickness 0.15)) (justify left bottom mirror))
    )
    (fp_text user "License: Apache-2.0" (at -0.932 -5.17) (layer "B.Fab") hide
        (effects (font (size 0.7 0.7) (thickness 0.15)) (justify left bottom mirror))
    )
    (fp_rect (start -0.94 0.47) (end 0.94 -0.47)
      (stroke (width 0.05) (type solid)) (fill none) (layer "B.CrtYd"))
    (fp_rect (start -0.499 0.249) (end 0.499 -0.249)
      (stroke (width 0.15) (type solid)) (fill none) (layer "B.Fab"))
    (pad "1" smd roundrect (at -0.484 0 180) (size 0.59 0.64) (layers "B.Cu" "B.Paste" "B.Mask") (roundrect_rratio 0.25)
      (net 250 "Net-(U47-SS)") (pintype "passive"))
    (pad "2" smd roundrect (at 0.484 0 180) (size 0.59 0.64) (layers "B.Cu" "B.Paste" "B.Mask") (roundrect_rratio 0.25)
      (net 1 "GND") (pintype "passive"))
  )
	(footprint "kria-k26-devboard-footprints:C_0402_1005Metric" (layer "B.Cu")
    (at 150.61 71.36)
    (descr "Capacitor SMD 0402")
    (tags "capacitor SMD 0402")
    (property "Author" "Antmicro")
    (property "Dielectric" "X5R")
    (property "License" "Apache-2.0")
    (property "MPN" "GRM155R61H104KE14D")
    (property "Manufacturer" "Murata")
    (property "Sheetfile" "dc-dc-conventers.kicad_sch")
    (property "Sheetname" "DC/DC conventers")
    (property "Val" "100n")
    (property "Voltage" "50V")
    (property "ki_description" " ")
    (attr smd)
    (fp_text reference "C191" (at 1.18 -0.58 180) (layer "B.SilkS")
        (effects (font (size 0.7 0.7) (thickness 0.15)) (justify left bottom mirror))
    )
    (fp_text value "C_100n_0402" (at 0 -1.4 180) (layer "B.Fab") hide
        (effects (font (size 0.7 0.7) (thickness 0.15)) (justify left bottom mirror))
    )
    (fp_text user "Author: Antmicro" (at -0.932 -4.17 180) (layer "B.Fab") hide
        (effects (font (size 0.7 0.7) (thickness 0.15)) (justify left bottom mirror))
    )
    (fp_text user "License: Apache-2.0" (at -0.932 -5.17 180) (layer "B.Fab") hide
        (effects (font (size 0.7 0.7) (thickness 0.15)) (justify left bottom mirror))
    )
    (fp_text user "${REFERENCE}" (at -0.932 -3.168 180) (layer "B.Fab") hide
        (effects (font (size 0.7 0.7) (thickness 0.15)) (justify left bottom mirror))
    )
    (fp_rect (start -0.94 0.47) (end 0.94 -0.47)
      (stroke (width 0.05) (type solid)) (fill none) (layer "B.CrtYd"))
    (fp_rect (start -0.499 0.249) (end 0.499 -0.249)
      (stroke (width 0.15) (type solid)) (fill none) (layer "B.Fab"))
    (pad "1" smd roundrect (at -0.484 0) (size 0.59 0.64) (layers "B.Cu" "B.Paste" "B.Mask") (roundrect_rratio 0.25)
      (net 252 "Net-(U47-BOOT)") (pintype "passive"))
    (pad "2" smd roundrect (at 0.484 0) (size 0.59 0.64) (layers "B.Cu" "B.Paste" "B.Mask") (roundrect_rratio 0.25)
      (net 365 "/Power Supply/DC/DC conventers/SW_USB_5V") (pintype "passive"))
  )
	(footprint "kria-k26-devboard-footprints:C_0402_1005Metric" (layer "B.Cu")
    (at 144.56 76.14 -90)
    (descr "Capacitor SMD 0402")
    (tags "capacitor SMD 0402")
    (property "Author" "Antmicro")
    (property "Dielectric" "")
    (property "License" "Apache-2.0")
    (property "MPN" "CC0402JRNPO9BN220")
    (property "Manufacturer" "Yaego")
    (property "Sheetfile" "dc-dc-conventers.kicad_sch")
    (property "Sheetname" "DC/DC conventers")
    (property "Val" "22p")
    (property "Voltage" "")
    (property "ki_description" " ")
    (attr smd)
    (fp_text reference "C193" (at -1.53 2.36 90) (layer "B.SilkS")
        (effects (font (size 0.7 0.7) (thickness 0.15)) (justify left bottom mirror))
    )
    (fp_text value "C_22p_0402" (at 0 -1.4 90) (layer "B.Fab") hide
        (effects (font (size 0.7 0.7) (thickness 0.15)) (justify left bottom mirror))
    )
    (fp_text user "License: Apache-2.0" (at -0.932 -5.17 90) (layer "B.Fab") hide
        (effects (font (size 0.7 0.7) (thickness 0.15)) (justify left bottom mirror))
    )
    (fp_text user "${REFERENCE}" (at -0.932 -3.168 90) (layer "B.Fab") hide
        (effects (font (size 0.7 0.7) (thickness 0.15)) (justify left bottom mirror))
    )
    (fp_text user "Author: Antmicro" (at -0.932 -4.17 90) (layer "B.Fab") hide
        (effects (font (size 0.7 0.7) (thickness 0.15)) (justify left bottom mirror))
    )
    (fp_rect (start -0.94 0.47) (end 0.94 -0.47)
      (stroke (width 0.05) (type solid)) (fill none) (layer "B.CrtYd"))
    (fp_rect (start -0.499 0.249) (end 0.499 -0.249)
      (stroke (width 0.15) (type solid)) (fill none) (layer "B.Fab"))
    (pad "1" smd roundrect (at -0.484 0 270) (size 0.59 0.64) (layers "B.Cu" "B.Paste" "B.Mask") (roundrect_rratio 0.25)
      (net 254 "Net-(U47-FB)") (pintype "passive"))
    (pad "2" smd roundrect (at 0.484 0 270) (size 0.59 0.64) (layers "B.Cu" "B.Paste" "B.Mask") (roundrect_rratio 0.25)
      (net 772 "/Power Supply/DC/DC conventers/USB_5V_OUT") (pintype "passive"))
  )
	(footprint "kria-k26-devboard-footprints:C_0603_1608Metric" (layer "B.Cu")
    (at 147.335 69.76 180)
    (descr "Capacitor SMD 0603")
    (tags "capacitor 0603")
    (property "Author" "Antmicro")
    (property "Dielectric" "")
    (property "License" "Apache-2.0")
    (property "MPN" "C1608X5R1E106M080AC")
    (property "Manufacturer" "TDK")
    (property "Sheetfile" "dc-dc-conventers.kicad_sch")
    (property "Sheetname" "DC/DC conventers")
    (property "Val" "10u/25V")
    (property "Voltage" "")
    (property "ki_description" " ")
    (attr smd)
    (fp_text reference "C183" (at -1.465 1.64) (layer "B.SilkS")
        (effects (font (size 0.7 0.7) (thickness 0.15)) (justify left bottom mirror))
    )
    (fp_text value "C_10u_25V_0603" (at 0 -1.6) (layer "B.Fab") hide
        (effects (font (size 0.7 0.7) (thickness 0.15)) (justify left bottom mirror))
    )
    (fp_text user "${REFERENCE}" (at -1.682 -3.895) (layer "B.Fab") hide
        (effects (font (size 0.7 0.7) (thickness 0.15)) (justify left bottom mirror))
    )
    (fp_text user "License: Apache-2.0" (at -1.682 -5.895) (layer "B.Fab") hide
        (effects (font (size 0.7 0.7) (thickness 0.15)) (justify left bottom mirror))
    )
    (fp_text user "Author: Antmicro" (at -1.682 -4.894) (layer "B.Fab") hide
        (effects (font (size 0.7 0.7) (thickness 0.15)) (justify left bottom mirror))
    )
    (fp_line (start -0.3 -0.3) (end 0.3 -0.3)
      (stroke (width 0.15) (type solid)) (layer "B.SilkS"))
    (fp_line (start -0.3 0.3) (end 0.3 0.3)
      (stroke (width 0.15) (type solid)) (layer "B.SilkS"))
    (fp_rect (start -1.24 0.7) (end 1.24 -0.7)
      (stroke (width 0.05) (type solid)) (fill none) (layer "B.CrtYd"))
    (fp_rect (start -0.8 0.4) (end 0.8 -0.4)
      (stroke (width 0.15) (type solid)) (fill none) (layer "B.Fab"))
    (pad "1" smd roundrect (at -0.7 0 180) (size 0.6 0.8) (layers "B.Cu" "B.Paste" "B.Mask") (roundrect_rratio 0.2)
      (net 14 "/Power Supply/DC/DC conventers/DC_MAIN_BUS") (pintype "passive"))
    (pad "2" smd roundrect (at 0.7 0 180) (size 0.6 0.8) (layers "B.Cu" "B.Paste" "B.Mask") (roundrect_rratio 0.2)
      (net 1 "GND") (pintype "passive"))
  )
	(footprint "kria-k26-devboard-footprints:L_Coilcraft-XEL4030" (layer "B.Cu")
    (at 151.875 74.3 -90)
    (property "Author" "Antmicro")
    (property "IMax" "")
    (property "ISat" "")
    (property "License" "Apache-2.0")
    (property "MPN" "XEL4030-332MEC")
    (property "Manufacturer" "Coilcraft")
    (property "Sheetfile" "dc-dc-conventers.kicad_sch")
    (property "Sheetname" "DC/DC conventers")
    (property "Size" "4x4")
    (property "Val" "3u3/5.9A")
    (attr smd)
    (fp_text reference "L1" (at 2.13 -3.595 180) (layer "B.SilkS")
        (effects (font (size 0.7 0.7) (thickness 0.15)) (justify left bottom mirror))
    )
    (fp_text value "L_3u3_5.9A_XEL4030" (at 0.05 -2.996 90) (layer "B.Fab") hide
        (effects (font (size 0.7 0.7) (thickness 0.15)) (justify left bottom mirror))
    )
    (fp_text user "${REFERENCE}" (at -2.15 -4.996 90) (layer "B.Fab") hide
        (effects (font (size 0.7 0.7) (thickness 0.15)) (justify left bottom mirror))
    )
    (fp_text user "Author: Antmicro" (at -2.15 -5.996 90) (layer "B.Fab") hide
        (effects (font (size 0.7 0.7) (thickness 0.15)) (justify left bottom mirror))
    )
    (fp_text user "License: Apache-2.0" (at -2.15 -6.996 90) (layer "B.Fab") hide
        (effects (font (size 0.7 0.7) (thickness 0.15)) (justify left bottom mirror))
    )
    (fp_line (start -1.8 -2.2) (end 1.85 -2.199)
      (stroke (width 0.15) (type solid)) (layer "B.SilkS"))
    (fp_line (start -1.8 2.2) (end 1.85 2.201)
      (stroke (width 0.15) (type solid)) (layer "B.SilkS"))
    (fp_rect (start -2.45 2.45) (end 2.45 -2.45)
      (stroke (width 0.05) (type solid)) (fill none) (layer "B.CrtYd"))
    (fp_line (start -2 -1.999) (end -2 2)
      (stroke (width 0.15) (type solid)) (layer "B.Fab"))
    (fp_line (start -2 2) (end 1.999 2)
      (stroke (width 0.15) (type solid)) (layer "B.Fab"))
    (fp_line (start 1.999 -1.999) (end -2 -1.999)
      (stroke (width 0.15) (type solid)) (layer "B.Fab"))
    (fp_line (start 1.999 2) (end 1.999 -1.999)
      (stroke (width 0.15) (type solid)) (layer "B.Fab"))
    (pad "1" smd rect (at -1.186 0 270) (size 0.98 3.4) (layers "B.Cu" "B.Paste" "B.Mask")
      (net 365 "/Power Supply/DC/DC conventers/SW_USB_5V") (pintype "passive"))
    (pad "2" smd rect (at 1.185 0 270) (size 0.98 3.4) (layers "B.Cu" "B.Paste" "B.Mask")
      (net 772 "/Power Supply/DC/DC conventers/USB_5V_OUT") (pintype "passive"))
  )
	(footprint "kria-k26-devboard-footprints:C_0603_1608Metric" (layer "B.Cu")
    (at 148.375 77.4 180)
    (descr "Capacitor SMD 0603")
    (tags "capacitor 0603")
    (property "Author" "Antmicro")
    (property "Dielectric" "")
    (property "License" "Apache-2.0")
    (property "MPN" "CL10A226MO7JZNC")
    (property "Manufacturer" "Samsung")
    (property "Sheetfile" "dc-dc-conventers.kicad_sch")
    (property "Sheetname" "DC/DC conventers")
    (property "Val" "22u/16V")
    (property "Voltage" "")
    (property "ki_description" " ")
    (attr smd)
    (fp_text reference "C197" (at -0.515 -2.28) (layer "B.SilkS")
        (effects (font (size 0.7 0.7) (thickness 0.15)) (justify left bottom mirror))
    )
    (fp_text value "C_22u_16V_0603" (at 0 -1.6) (layer "B.Fab") hide
        (effects (font (size 0.7 0.7) (thickness 0.15)) (justify left bottom mirror))
    )
    (fp_text user "Author: Antmicro" (at -1.682 -4.894) (layer "B.Fab") hide
        (effects (font (size 0.7 0.7) (thickness 0.15)) (justify left bottom mirror))
    )
    (fp_text user "${REFERENCE}" (at -1.682 -3.895) (layer "B.Fab") hide
        (effects (font (size 0.7 0.7) (thickness 0.15)) (justify left bottom mirror))
    )
    (fp_text user "License: Apache-2.0" (at -1.682 -5.895) (layer "B.Fab") hide
        (effects (font (size 0.7 0.7) (thickness 0.15)) (justify left bottom mirror))
    )
    (fp_line (start -0.3 -0.3) (end 0.3 -0.3)
      (stroke (width 0.15) (type solid)) (layer "B.SilkS"))
    (fp_line (start -0.3 0.3) (end 0.3 0.3)
      (stroke (width 0.15) (type solid)) (layer "B.SilkS"))
    (fp_rect (start -1.24 0.7) (end 1.24 -0.7)
      (stroke (width 0.05) (type solid)) (fill none) (layer "B.CrtYd"))
    (fp_rect (start -0.8 0.4) (end 0.8 -0.4)
      (stroke (width 0.15) (type solid)) (fill none) (layer "B.Fab"))
    (pad "1" smd roundrect (at -0.7 0 180) (size 0.6 0.8) (layers "B.Cu" "B.Paste" "B.Mask") (roundrect_rratio 0.2)
      (net 772 "/Power Supply/DC/DC conventers/USB_5V_OUT") (pintype "passive"))
    (pad "2" smd roundrect (at 0.7 0 180) (size 0.6 0.8) (layers "B.Cu" "B.Paste" "B.Mask") (roundrect_rratio 0.2)
      (net 1 "GND") (pintype "passive"))
  )
	(footprint "kria-k26-devboard-footprints:C_0603_1608Metric" (layer "B.Cu")
    (at 148.375 75.95 180)
    (descr "Capacitor SMD 0603")
    (tags "capacitor 0603")
    (property "Author" "Antmicro")
    (property "Dielectric" "")
    (property "License" "Apache-2.0")
    (property "MPN" "CL10A226MO7JZNC")
    (property "Manufacturer" "Samsung")
    (property "Sheetfile" "dc-dc-conventers.kicad_sch")
    (property "Sheetname" "DC/DC conventers")
    (property "Val" "22u/16V")
    (property "Voltage" "")
    (property "ki_description" " ")
    (attr smd)
    (fp_text reference "C199" (at -0.515 -2.86) (layer "B.SilkS")
        (effects (font (size 0.7 0.7) (thickness 0.15)) (justify left bottom mirror))
    )
    (fp_text value "C_22u_16V_0603" (at 0 -1.6) (layer "B.Fab") hide
        (effects (font (size 0.7 0.7) (thickness 0.15)) (justify left bottom mirror))
    )
    (fp_text user "Author: Antmicro" (at -1.682 -4.894) (layer "B.Fab") hide
        (effects (font (size 0.7 0.7) (thickness 0.15)) (justify left bottom mirror))
    )
    (fp_text user "${REFERENCE}" (at -1.682 -3.895) (layer "B.Fab") hide
        (effects (font (size 0.7 0.7) (thickness 0.15)) (justify left bottom mirror))
    )
    (fp_text user "License: Apache-2.0" (at -1.682 -5.895) (layer "B.Fab") hide
        (effects (font (size 0.7 0.7) (thickness 0.15)) (justify left bottom mirror))
    )
    (fp_line (start -0.3 -0.3) (end 0.3 -0.3)
      (stroke (width 0.15) (type solid)) (layer "B.SilkS"))
    (fp_line (start -0.3 0.3) (end 0.3 0.3)
      (stroke (width 0.15) (type solid)) (layer "B.SilkS"))
    (fp_rect (start -1.24 0.7) (end 1.24 -0.7)
      (stroke (width 0.05) (type solid)) (fill none) (layer "B.CrtYd"))
    (fp_rect (start -0.8 0.4) (end 0.8 -0.4)
      (stroke (width 0.15) (type solid)) (fill none) (layer "B.Fab"))
    (pad "1" smd roundrect (at -0.7 0 180) (size 0.6 0.8) (layers "B.Cu" "B.Paste" "B.Mask") (roundrect_rratio 0.2)
      (net 772 "/Power Supply/DC/DC conventers/USB_5V_OUT") (pintype "passive"))
    (pad "2" smd roundrect (at 0.7 0 180) (size 0.6 0.8) (layers "B.Cu" "B.Paste" "B.Mask") (roundrect_rratio 0.2)
      (net 1 "GND") (pintype "passive"))
  )
)
